(kicad_pcb
	(version 20260206)
	(generator "pcbnew")
	(generator_version "10.0")
	(general
		(thickness 1.6)
		(legacy_teardrops no)
	)
	(paper "A4")
	(title_block
		(title "Bryce Canyon_IOM_M2_16342-2_OCP.brd")
		(comment 1 "Bryce Canyon / footprints 429-434 of 1146")
	)
	(layers
		(0 "F.Cu" signal "TOP")
		(4 "In1.Cu" signal "L2GND")
		(6 "In2.Cu" signal "L3")
		(8 "In3.Cu" signal "L4VCC")
		(10 "In4.Cu" signal "L5VCC")
		(12 "In5.Cu" signal "L6")
		(14 "In6.Cu" signal "L7GND")
		(2 "B.Cu" signal "BOTTOM")
		(9 "F.Adhes" user "F.Adhesive")
		(11 "B.Adhes" user "B.Adhesive")
		(13 "F.Paste" user "Package Geometry/Pastemask Top")
		(15 "B.Paste" user "Package Geometry/Pastemask Bottom")
		(5 "F.SilkS" user "Ref Des/Silkscreen Top")
		(7 "B.SilkS" user "Ref Des/Silkscreen Bottom")
		(1 "F.Mask" user "Board Geometry/Soldermask Top")
		(3 "B.Mask" user "Board Geometry/Soldermask Bottom")
		(17 "Dwgs.User" user "User.Drawings")
		(19 "Cmts.User" user "User.Comments")
		(21 "Eco1.User" user "User.Eco1")
		(23 "Eco2.User" user "User.Eco2")
		(25 "Edge.Cuts" user "Board Geometry/Outline")
		(27 "Margin" user)
		(31 "F.CrtYd" user "Package Geometry/Place Bound Top")
		(29 "B.CrtYd" user "Package Geometry/Place Bound Bottom")
		(35 "F.Fab" user "Ref Des/Assembly Top")
		(33 "B.Fab" user "Ref Des/Assembly Bottom")
	)
	(footprint ""
		(layer "F.Cu")
		(at 72.4408 -133.9342 90)
		(property "Reference" "R105"
			(at 0 0 90)
			(layer "F.SilkS")
			(hide yes)
			(effects
				(font
					(size 1.27 1.27)
				)
			)
		)
		(property "Value" "4K7R2F-GP"
			(at 0.064008 -3.993896 90)
			(unlocked yes)
			(layer "F.Fab")
			(hide yes)
			(effects
				(font
					(size 1.016 1.016)
					(thickness 0.1524)
				)
			)
		)
		(property "Device Type" "R402H16"
			(at 0.064008 -5.517896 90)
			(unlocked yes)
			(layer "F.Fab")
			(hide yes)
			(effects
				(font
					(size 1.016 1.016)
					(thickness 0.1524)
				)
			)
		)
		(duplicate_pad_numbers_are_jumpers no)
		(fp_line
			(start 0.508 -0.9398)
			(end -0.508 -0.9398)
			(stroke
				(width 0.1524)
				(type default)
			)
			(layer "F.SilkS")
		)
		(fp_line
			(start -0.508 -0.9398)
			(end -0.508 0.9398)
			(stroke
				(width 0.1524)
				(type default)
			)
			(layer "F.SilkS")
		)
		(fp_rect
			(start -0.508 0.9398)
			(end 0.508 -0.9398)
			(stroke
				(width 0)
				(type default)
			)
			(fill no)
			(layer "F.CrtYd")
		)
		(fp_rect
			(start -0.508 0.9398)
			(end 0.508 -0.9398)
			(stroke
				(width 0)
				(type default)
			)
			(fill no)
			(layer "F.Fab")
		)
		(pad "1" smd custom
			(at 0 -0.4445 90)
			(size 0.1397 0.1397)
			(layers "F.Cu" "F.Mask" "F.Paste")
			(net "P3V3_STBY")
			(options
				(clearance outline)
				(anchor circle)
			)
			(primitives
				(gr_poly
					(pts
						(arc
							(start -0.1778 -0.2794)
							(mid -0.249642 -0.249642)
							(end -0.2794 -0.1778)
						)
						(arc
							(start -0.2794 0.1778)
							(mid -0.249642 0.249642)
							(end -0.1778 0.2794)
						)
						(arc
							(start 0.1778 0.2794)
							(mid 0.249642 0.249642)
							(end 0.2794 0.1778)
						)
						(arc
							(start 0.2794 -0.1778)
							(mid 0.249642 -0.249642)
							(end 0.1778 -0.2794)
						)
					)
					(width 0)
					(fill yes)
				)
			)
		)
		(pad "2" smd custom
			(at 0 0.4445 90)
			(size 0.1397 0.1397)
			(layers "F.Cu" "F.Mask" "F.Paste")
			(net "D_FLIP_CLR#")
			(options
				(clearance outline)
				(anchor circle)
			)
			(primitives
				(gr_poly
					(pts
						(arc
							(start -0.1778 -0.2794)
							(mid -0.249642 -0.249642)
							(end -0.2794 -0.1778)
						)
						(arc
							(start -0.2794 0.1778)
							(mid -0.249642 0.249642)
							(end -0.1778 0.2794)
						)
						(arc
							(start 0.1778 0.2794)
							(mid 0.249642 0.249642)
							(end 0.2794 0.1778)
						)
						(arc
							(start 0.2794 -0.1778)
							(mid 0.249642 -0.249642)
							(end 0.1778 -0.2794)
						)
					)
					(width 0)
					(fill yes)
				)
			)
		)
	)
	(footprint ""
		(layer "F.Cu")
		(at 48.216312 -163.566602 90)
		(property "Reference" "R367"
			(at 0 0 90)
			(layer "F.SilkS")
			(hide yes)
			(effects
				(font
					(size 1.27 1.27)
				)
			)
		)
		(property "Value" "18KR2F-5-GP"
			(at 0.064008 -3.993896 90)
			(unlocked yes)
			(layer "F.Fab")
			(hide yes)
			(effects
				(font
					(size 1.016 1.016)
					(thickness 0.1524)
				)
			)
		)
		(property "Device Type" "R402H16"
			(at 0.064008 -5.517896 90)
			(unlocked yes)
			(layer "F.Fab")
			(hide yes)
			(effects
				(font
					(size 1.016 1.016)
					(thickness 0.1524)
				)
			)
		)
		(duplicate_pad_numbers_are_jumpers no)
		(fp_line
			(start 0.508 -0.9398)
			(end -0.508 -0.9398)
			(stroke
				(width 0.1524)
				(type default)
			)
			(layer "F.SilkS")
		)
		(fp_line
			(start -0.508 -0.9398)
			(end -0.508 0.9398)
			(stroke
				(width 0.1524)
				(type default)
			)
			(layer "F.SilkS")
		)
		(fp_rect
			(start -0.508 0.9398)
			(end 0.508 -0.9398)
			(stroke
				(width 0)
				(type default)
			)
			(fill no)
			(layer "F.CrtYd")
		)
		(fp_rect
			(start -0.508 0.9398)
			(end 0.508 -0.9398)
			(stroke
				(width 0)
				(type default)
			)
			(fill no)
			(layer "F.Fab")
		)
		(pad "1" smd custom
			(at 0 -0.4445 90)
			(size 0.1397 0.1397)
			(layers "F.Cu" "F.Mask" "F.Paste")
			(net "GND")
			(options
				(clearance outline)
				(anchor circle)
			)
			(primitives
				(gr_poly
					(pts
						(arc
							(start -0.1778 -0.2794)
							(mid -0.249642 -0.249642)
							(end -0.2794 -0.1778)
						)
						(arc
							(start -0.2794 0.1778)
							(mid -0.249642 0.249642)
							(end -0.1778 0.2794)
						)
						(arc
							(start 0.1778 0.2794)
							(mid 0.249642 0.249642)
							(end 0.2794 0.1778)
						)
						(arc
							(start 0.2794 -0.1778)
							(mid 0.249642 -0.249642)
							(end 0.1778 -0.2794)
						)
					)
					(width 0)
					(fill yes)
				)
			)
		)
		(pad "2" smd custom
			(at 0 0.4445 90)
			(size 0.1397 0.1397)
			(layers "F.Cu" "F.Mask" "F.Paste")
			(net "DACRSET")
			(options
				(clearance outline)
				(anchor circle)
			)
			(primitives
				(gr_poly
					(pts
						(arc
							(start -0.1778 -0.2794)
							(mid -0.249642 -0.249642)
							(end -0.2794 -0.1778)
						)
						(arc
							(start -0.2794 0.1778)
							(mid -0.249642 0.249642)
							(end -0.1778 0.2794)
						)
						(arc
							(start 0.1778 0.2794)
							(mid 0.249642 0.249642)
							(end 0.2794 0.1778)
						)
						(arc
							(start 0.2794 -0.1778)
							(mid 0.249642 -0.249642)
							(end 0.1778 -0.2794)
						)
					)
					(width 0)
					(fill yes)
				)
			)
		)
	)
	(footprint ""
		(layer "F.Cu")
		(at 129.29997 -6.401308)
		(property "Reference" "R455"
			(at 0 0 0)
			(layer "F.SilkS")
			(hide yes)
			(effects
				(font
					(size 1.27 1.27)
				)
			)
		)
		(property "Value" "1MR3J-L-GP"
			(at -0.0254 -2.5146 0)
			(unlocked yes)
			(layer "F.Fab")
			(hide yes)
			(effects
				(font
					(size 1.016 1.016)
					(thickness 0.1524)
				)
			)
		)
		(property "Device Type" "R603H22"
			(at -0.0254 -4.0386 0)
			(unlocked yes)
			(layer "F.Fab")
			(hide yes)
			(effects
				(font
					(size 1.016 1.016)
					(thickness 0.1524)
				)
			)
		)
		(duplicate_pad_numbers_are_jumpers no)
		(fp_line
			(start -0.4826 0)
			(end -0.2032 0)
			(stroke
				(width 0.2032)
				(type default)
			)
			(layer "F.SilkS")
		)
		(fp_line
			(start 0.2032 0)
			(end 0.4826 0)
			(stroke
				(width 0.2032)
				(type default)
			)
			(layer "F.SilkS")
		)
		(fp_rect
			(start -0.5842 1.3335)
			(end 0.5842 -1.3335)
			(stroke
				(width 0)
				(type default)
			)
			(fill no)
			(layer "F.CrtYd")
		)
		(fp_rect
			(start -0.5842 1.3335)
			(end 0.5842 -1.3335)
			(stroke
				(width 0)
				(type default)
			)
			(fill no)
			(layer "F.Fab")
		)
		(pad "1" smd custom
			(at 0 -0.762)
			(size 0.2159 0.2159)
			(layers "F.Cu" "F.Mask" "F.Paste")
			(net "MB0_CM_GATE_R")
			(options
				(clearance outline)
				(anchor circle)
			)
			(primitives
				(gr_poly
					(pts
						(arc
							(start -0.3302 -0.4318)
							(mid -0.402042 -0.402042)
							(end -0.4318 -0.3302)
						)
						(arc
							(start -0.4318 0.3302)
							(mid -0.402042 0.402042)
							(end -0.3302 0.4318)
						)
						(arc
							(start 0.3302 0.4318)
							(mid 0.402042 0.402042)
							(end 0.4318 0.3302)
						)
						(arc
							(start 0.4318 -0.3302)
							(mid 0.402042 -0.402042)
							(end 0.3302 -0.4318)
						)
					)
					(width 0)
					(fill yes)
				)
			)
		)
		(pad "2" smd custom
			(at 0 0.762)
			(size 0.2159 0.2159)
			(layers "F.Cu" "F.Mask" "F.Paste")
			(net "GND")
			(options
				(clearance outline)
				(anchor circle)
			)
			(primitives
				(gr_poly
					(pts
						(arc
							(start -0.3302 -0.4318)
							(mid -0.402042 -0.402042)
							(end -0.4318 -0.3302)
						)
						(arc
							(start -0.4318 0.3302)
							(mid -0.402042 0.402042)
							(end -0.3302 0.4318)
						)
						(arc
							(start 0.3302 0.4318)
							(mid 0.402042 0.402042)
							(end 0.4318 0.3302)
						)
						(arc
							(start 0.4318 -0.3302)
							(mid 0.402042 -0.402042)
							(end 0.3302 -0.4318)
						)
					)
					(width 0)
					(fill yes)
				)
			)
		)
	)
	(footprint ""
		(layer "F.Cu")
		(at 61.3664 -152.654 90)
		(property "Reference" "R340"
			(at 0 0 90)
			(layer "F.SilkS")
			(hide yes)
			(effects
				(font
					(size 1.27 1.27)
				)
			)
		)
		(property "Value" "8K2R2J-3-GP"
			(at 0.064008 -3.993896 90)
			(unlocked yes)
			(layer "F.Fab")
			(hide yes)
			(effects
				(font
					(size 1.016 1.016)
					(thickness 0.1524)
				)
			)
		)
		(property "Device Type" "R402H16"
			(at 0.064008 -5.517896 90)
			(unlocked yes)
			(layer "F.Fab")
			(hide yes)
			(effects
				(font
					(size 1.016 1.016)
					(thickness 0.1524)
				)
			)
		)
		(duplicate_pad_numbers_are_jumpers no)
		(fp_line
			(start 0.508 -0.9398)
			(end -0.508 -0.9398)
			(stroke
				(width 0.1524)
				(type default)
			)
			(layer "F.SilkS")
		)
		(fp_line
			(start -0.508 -0.9398)
			(end -0.508 0.9398)
			(stroke
				(width 0.1524)
				(type default)
			)
			(layer "F.SilkS")
		)
		(fp_rect
			(start -0.508 0.9398)
			(end 0.508 -0.9398)
			(stroke
				(width 0)
				(type default)
			)
			(fill no)
			(layer "F.CrtYd")
		)
		(fp_rect
			(start -0.508 0.9398)
			(end 0.508 -0.9398)
			(stroke
				(width 0)
				(type default)
			)
			(fill no)
			(layer "F.Fab")
		)
		(pad "1" smd custom
			(at 0 -0.4445 90)
			(size 0.1397 0.1397)
			(layers "F.Cu" "F.Mask" "F.Paste")
			(net "PD_USB2BVRES")
			(options
				(clearance outline)
				(anchor circle)
			)
			(primitives
				(gr_poly
					(pts
						(arc
							(start -0.1778 -0.2794)
							(mid -0.249642 -0.249642)
							(end -0.2794 -0.1778)
						)
						(arc
							(start -0.2794 0.1778)
							(mid -0.249642 0.249642)
							(end -0.1778 0.2794)
						)
						(arc
							(start 0.1778 0.2794)
							(mid 0.249642 0.249642)
							(end 0.2794 0.1778)
						)
						(arc
							(start 0.2794 -0.1778)
							(mid 0.249642 -0.249642)
							(end 0.1778 -0.2794)
						)
					)
					(width 0)
					(fill yes)
				)
			)
		)
		(pad "2" smd custom
			(at 0 0.4445 90)
			(size 0.1397 0.1397)
			(layers "F.Cu" "F.Mask" "F.Paste")
			(net "GND")
			(options
				(clearance outline)
				(anchor circle)
			)
			(primitives
				(gr_poly
					(pts
						(arc
							(start -0.1778 -0.2794)
							(mid -0.249642 -0.249642)
							(end -0.2794 -0.1778)
						)
						(arc
							(start -0.2794 0.1778)
							(mid -0.249642 0.249642)
							(end -0.1778 0.2794)
						)
						(arc
							(start 0.1778 0.2794)
							(mid 0.249642 0.249642)
							(end 0.2794 0.1778)
						)
						(arc
							(start 0.2794 -0.1778)
							(mid 0.249642 -0.249642)
							(end 0.1778 -0.2794)
						)
					)
					(width 0)
					(fill yes)
				)
			)
		)
	)
	(footprint ""
		(layer "F.Cu")
		(at 63.5762 -145.669 90)
		(property "Reference" "R182"
			(at 0 0 90)
			(layer "F.SilkS")
			(hide yes)
			(effects
				(font
					(size 1.27 1.27)
				)
			)
		)
		(property "Value" "2K2R2F-GP"
			(at 0.064008 -3.993896 90)
			(unlocked yes)
			(layer "F.Fab")
			(hide yes)
			(effects
				(font
					(size 1.016 1.016)
					(thickness 0.1524)
				)
			)
		)
		(property "Device Type" "R402H16"
			(at 0.064008 -5.517896 90)
			(unlocked yes)
			(layer "F.Fab")
			(hide yes)
			(effects
				(font
					(size 1.016 1.016)
					(thickness 0.1524)
				)
			)
		)
		(duplicate_pad_numbers_are_jumpers no)
		(fp_line
			(start 0.508 -0.9398)
			(end -0.508 -0.9398)
			(stroke
				(width 0.1524)
				(type default)
			)
			(layer "F.SilkS")
		)
		(fp_line
			(start -0.508 -0.9398)
			(end -0.508 0.9398)
			(stroke
				(width 0.1524)
				(type default)
			)
			(layer "F.SilkS")
		)
		(fp_rect
			(start -0.508 0.9398)
			(end 0.508 -0.9398)
			(stroke
				(width 0)
				(type default)
			)
			(fill no)
			(layer "F.CrtYd")
		)
		(fp_rect
			(start -0.508 0.9398)
			(end 0.508 -0.9398)
			(stroke
				(width 0)
				(type default)
			)
			(fill no)
			(layer "F.Fab")
		)
		(pad "1" smd custom
			(at 0 -0.4445 90)
			(size 0.1397 0.1397)
			(layers "F.Cu" "F.Mask" "F.Paste")
			(net "I2C_SCC_SDA_OUT")
			(options
				(clearance outline)
				(anchor circle)
			)
			(primitives
				(gr_poly
					(pts
						(arc
							(start -0.1778 -0.2794)
							(mid -0.249642 -0.249642)
							(end -0.2794 -0.1778)
						)
						(arc
							(start -0.2794 0.1778)
							(mid -0.249642 0.249642)
							(end -0.1778 0.2794)
						)
						(arc
							(start 0.1778 0.2794)
							(mid 0.249642 0.249642)
							(end 0.2794 0.1778)
						)
						(arc
							(start 0.2794 -0.1778)
							(mid 0.249642 -0.249642)
							(end 0.1778 -0.2794)
						)
					)
					(width 0)
					(fill yes)
				)
			)
		)
		(pad "2" smd custom
			(at 0 0.4445 90)
			(size 0.1397 0.1397)
			(layers "F.Cu" "F.Mask" "F.Paste")
			(net "P3V3_STBY")
			(options
				(clearance outline)
				(anchor circle)
			)
			(primitives
				(gr_poly
					(pts
						(arc
							(start -0.1778 -0.2794)
							(mid -0.249642 -0.249642)
							(end -0.2794 -0.1778)
						)
						(arc
							(start -0.2794 0.1778)
							(mid -0.249642 0.249642)
							(end -0.1778 0.2794)
						)
						(arc
							(start 0.1778 0.2794)
							(mid 0.249642 0.249642)
							(end 0.2794 0.1778)
						)
						(arc
							(start 0.2794 -0.1778)
							(mid 0.249642 -0.249642)
							(end 0.1778 -0.2794)
						)
					)
					(width 0)
					(fill yes)
				)
			)
		)
	)
	(footprint ""
		(layer "F.Cu")
		(at 69.62775 -137.444734 90)
		(property "Reference" "R49"
			(at 0 0 90)
			(layer "F.SilkS")
			(hide yes)
			(effects
				(font
					(size 1.27 1.27)
				)
			)
		)
		(property "Value" "10KR2F-2-GP"
			(at 0.064008 -3.993896 90)
			(unlocked yes)
			(layer "F.Fab")
			(hide yes)
			(effects
				(font
					(size 1.016 1.016)
					(thickness 0.1524)
				)
			)
		)
		(property "Device Type" "R402H16"
			(at 0.064008 -5.517896 90)
			(unlocked yes)
			(layer "F.Fab")
			(hide yes)
			(effects
				(font
					(size 1.016 1.016)
					(thickness 0.1524)
				)
			)
		)
		(duplicate_pad_numbers_are_jumpers no)
		(fp_line
			(start 0.508 -0.9398)
			(end -0.508 -0.9398)
			(stroke
				(width 0.1524)
				(type default)
			)
			(layer "F.SilkS")
		)
		(fp_line
			(start -0.508 -0.9398)
			(end -0.508 0.9398)
			(stroke
				(width 0.1524)
				(type default)
			)
			(layer "F.SilkS")
		)
		(fp_rect
			(start -0.508 0.9398)
			(end 0.508 -0.9398)
			(stroke
				(width 0)
				(type default)
			)
			(fill no)
			(layer "F.CrtYd")
		)
		(fp_rect
			(start -0.508 0.9398)
			(end 0.508 -0.9398)
			(stroke
				(width 0)
				(type default)
			)
			(fill no)
			(layer "F.Fab")
		)
		(pad "1" smd custom
			(at 0 -0.4445 90)
			(size 0.1397 0.1397)
			(layers "F.Cu" "F.Mask" "F.Paste")
			(net "P3V3_STBY")
			(options
				(clearance outline)
				(anchor circle)
			)
			(primitives
				(gr_poly
					(pts
						(arc
							(start -0.1778 -0.2794)
							(mid -0.249642 -0.249642)
							(end -0.2794 -0.1778)
						)
						(arc
							(start -0.2794 0.1778)
							(mid -0.249642 0.249642)
							(end -0.1778 0.2794)
						)
						(arc
							(start 0.1778 0.2794)
							(mid 0.249642 0.249642)
							(end 0.2794 0.1778)
						)
						(arc
							(start 0.2794 -0.1778)
							(mid 0.249642 -0.249642)
							(end 0.1778 -0.2794)
						)
					)
					(width 0)
					(fill yes)
				)
			)
		)
		(pad "2" smd custom
			(at 0 0.4445 90)
			(size 0.1397 0.1397)
			(layers "F.Cu" "F.Mask" "F.Paste")
			(net "FP_PWRBTN")
			(options
				(clearance outline)
				(anchor circle)
			)
			(primitives
				(gr_poly
					(pts
						(arc
							(start -0.1778 -0.2794)
							(mid -0.249642 -0.249642)
							(end -0.2794 -0.1778)
						)
						(arc
							(start -0.2794 0.1778)
							(mid -0.249642 0.249642)
							(end -0.1778 0.2794)
						)
						(arc
							(start 0.1778 0.2794)
							(mid 0.249642 0.249642)
							(end 0.2794 0.1778)
						)
						(arc
							(start 0.2794 -0.1778)
							(mid 0.249642 -0.249642)
							(end 0.1778 -0.2794)
						)
					)
					(width 0)
					(fill yes)
				)
			)
		)
	)
)
